(kicad_pcb
	(version 20260206)
	(generator "pcbnew")
	(generator_version "10.0")
	(general
		(thickness 1.6)
		(legacy_teardrops no)
	)
	(paper "A4")
	(title_block
		(title "01162023_DA0F0TEBIF0_F0T_Expander_BD_F_brd_V02_OCP.brd")
		(comment 1 "Grand Teton / footprints 3622-3627 of 9728")
	)
	(layers
		(0 "F.Cu" signal "TOP")
		(4 "In1.Cu" signal "GND")
		(6 "In2.Cu" signal "VCC")
		(8 "In3.Cu" signal "VCC1")
		(10 "In4.Cu" signal "GND1")
		(12 "In5.Cu" signal "IN1")
		(14 "In6.Cu" signal "GND2")
		(16 "In7.Cu" signal "IN2")
		(18 "In8.Cu" signal "GND3")
		(20 "In9.Cu" signal "IN3")
		(22 "In10.Cu" signal "GND4")
		(24 "In11.Cu" signal "IN4")
		(26 "In12.Cu" signal "GND5")
		(28 "In13.Cu" signal "IN5")
		(30 "In14.Cu" signal "GND6")
		(32 "In15.Cu" signal "IN6")
		(34 "In16.Cu" signal "GND7")
		(2 "B.Cu" signal "BOTTOM")
		(9 "F.Adhes" user "F.Adhesive")
		(11 "B.Adhes" user "B.Adhesive")
		(13 "F.Paste" user "Package Geometry/Pastemask Top")
		(15 "B.Paste" user "Package Geometry/Pastemask Bottom")
		(5 "F.SilkS" user "Ref Des/Silkscreen Top")
		(7 "B.SilkS" user "Ref Des/Silkscreen Bottom")
		(1 "F.Mask" user "Board Geometry/Soldermask Top")
		(3 "B.Mask" user "Board Geometry/Soldermask Bottom")
		(17 "Dwgs.User" user "User.Drawings")
		(19 "Cmts.User" user "User.Comments")
		(21 "Eco1.User" user "User.Eco1")
		(23 "Eco2.User" user "User.Eco2")
		(25 "Edge.Cuts" user "Board Geometry/Outline")
		(27 "Margin" user)
		(31 "F.CrtYd" user "Package Geometry/Place Bound Top")
		(29 "B.CrtYd" user "Package Geometry/Place Bound Bottom")
		(35 "F.Fab" user "Ref Des/Assembly Top")
		(33 "B.Fab" user "Ref Des/Assembly Bottom")
	)
	(footprint ""
		(layer "F.Cu")
		(at 413.766508 -189.056518 180)
		(property "Reference" "R6425"
			(at 0 0 180)
			(layer "F.SilkS")
			(hide yes)
			(effects
				(font
					(size 1.27 1.27)
				)
			)
		)
		(property "Value" ""
			(at 0 0 180)
			(layer "F.Fab")
			(effects
				(font
					(size 1.27 1.27)
				)
			)
		)
		(duplicate_pad_numbers_are_jumpers no)
		(fp_line
			(start 0.7874 0.4064)
			(end -0.7874 0.4064)
			(stroke
				(width 0.1524)
				(type default)
			)
			(layer "F.SilkS")
		)
		(fp_line
			(start 0.7874 -0.4064)
			(end 0.7874 0.4064)
			(stroke
				(width 0.1524)
				(type default)
			)
			(layer "F.SilkS")
		)
		(fp_line
			(start -0.7874 0.4064)
			(end -0.7874 -0.4064)
			(stroke
				(width 0.1524)
				(type default)
			)
			(layer "F.SilkS")
		)
		(fp_line
			(start -0.7874 -0.4064)
			(end 0.7874 -0.4064)
			(stroke
				(width 0.1524)
				(type default)
			)
			(layer "F.SilkS")
		)
		(fp_line
			(start 0.67945 0.3048)
			(end 0.120396 0.3048)
			(stroke
				(width 0.1)
				(type default)
			)
			(layer "F.Fab")
		)
		(fp_line
			(start 0.67945 -0.3048)
			(end 0.67945 0.3048)
			(stroke
				(width 0.1)
				(type default)
			)
			(layer "F.Fab")
		)
		(fp_line
			(start 0.12065 -0.2794)
			(end 0.12065 -0.3048)
			(stroke
				(width 0.1)
				(type default)
			)
			(layer "F.Fab")
		)
		(fp_line
			(start 0.12065 -0.3048)
			(end 0.67945 -0.3048)
			(stroke
				(width 0.1)
				(type default)
			)
			(layer "F.Fab")
		)
		(fp_line
			(start 0.120396 0.3048)
			(end 0.120396 0.2794)
			(stroke
				(width 0.1)
				(type default)
			)
			(layer "F.Fab")
		)
		(fp_line
			(start 0.120396 0.2794)
			(end -0.12065 0.2794)
			(stroke
				(width 0.1)
				(type default)
			)
			(layer "F.Fab")
		)
		(fp_line
			(start -0.12065 0.3048)
			(end -0.67945 0.3048)
			(stroke
				(width 0.1)
				(type default)
			)
			(layer "F.Fab")
		)
		(fp_line
			(start -0.12065 0.2794)
			(end -0.12065 0.3048)
			(stroke
				(width 0.1)
				(type default)
			)
			(layer "F.Fab")
		)
		(fp_line
			(start -0.12065 -0.2794)
			(end 0.12065 -0.2794)
			(stroke
				(width 0.1)
				(type default)
			)
			(layer "F.Fab")
		)
		(fp_line
			(start -0.12065 -0.305054)
			(end -0.12065 -0.2794)
			(stroke
				(width 0.1)
				(type default)
			)
			(layer "F.Fab")
		)
		(fp_line
			(start -0.67945 0.3048)
			(end -0.67945 -0.305054)
			(stroke
				(width 0.1)
				(type default)
			)
			(layer "F.Fab")
		)
		(fp_line
			(start -0.67945 -0.305054)
			(end -0.12065 -0.305054)
			(stroke
				(width 0.1)
				(type default)
			)
			(layer "F.Fab")
		)
		(pad "1" smd circle
			(at -0.40005 0 180)
			(size 0 0)
			(layers "F.Cu" "F.Mask" "F.Paste")
			(net "FPGA_PEX0_MODE_SEL2_D_N")
		)
		(pad "2" smd circle
			(at 0.40005 0 180)
			(size 0 0)
			(layers "F.Cu" "F.Mask" "F.Paste")
			(net "P3V3_AUX")
		)
	)
	(footprint ""
		(layer "F.Cu")
		(at 110.635796 -111.896906 90)
		(property "Reference" "PR6872"
			(at 0 0 90)
			(layer "F.SilkS")
			(hide yes)
			(effects
				(font
					(size 1.27 1.27)
				)
			)
		)
		(property "Value" ""
			(at 0 0 90)
			(layer "F.Fab")
			(effects
				(font
					(size 1.27 1.27)
				)
			)
		)
		(duplicate_pad_numbers_are_jumpers no)
		(fp_line
			(start 0.7874 -0.4064)
			(end 0.7874 0.4064)
			(stroke
				(width 0.1524)
				(type default)
			)
			(layer "F.SilkS")
		)
		(fp_line
			(start -0.7874 -0.4064)
			(end 0.7874 -0.4064)
			(stroke
				(width 0.1524)
				(type default)
			)
			(layer "F.SilkS")
		)
		(fp_line
			(start 0.7874 0.4064)
			(end -0.7874 0.4064)
			(stroke
				(width 0.1524)
				(type default)
			)
			(layer "F.SilkS")
		)
		(fp_line
			(start -0.7874 0.4064)
			(end -0.7874 -0.4064)
			(stroke
				(width 0.1524)
				(type default)
			)
			(layer "F.SilkS")
		)
		(fp_line
			(start -0.12065 -0.305054)
			(end -0.12065 -0.2794)
			(stroke
				(width 0.1)
				(type default)
			)
			(layer "F.Fab")
		)
		(fp_line
			(start -0.67945 -0.305054)
			(end -0.12065 -0.305054)
			(stroke
				(width 0.1)
				(type default)
			)
			(layer "F.Fab")
		)
		(fp_line
			(start 0.67945 -0.3048)
			(end 0.67945 0.3048)
			(stroke
				(width 0.1)
				(type default)
			)
			(layer "F.Fab")
		)
		(fp_line
			(start 0.12065 -0.3048)
			(end 0.67945 -0.3048)
			(stroke
				(width 0.1)
				(type default)
			)
			(layer "F.Fab")
		)
		(fp_line
			(start 0.12065 -0.2794)
			(end 0.12065 -0.3048)
			(stroke
				(width 0.1)
				(type default)
			)
			(layer "F.Fab")
		)
		(fp_line
			(start -0.12065 -0.2794)
			(end 0.12065 -0.2794)
			(stroke
				(width 0.1)
				(type default)
			)
			(layer "F.Fab")
		)
		(fp_line
			(start 0.120396 0.2794)
			(end -0.12065 0.2794)
			(stroke
				(width 0.1)
				(type default)
			)
			(layer "F.Fab")
		)
		(fp_line
			(start -0.12065 0.2794)
			(end -0.12065 0.3048)
			(stroke
				(width 0.1)
				(type default)
			)
			(layer "F.Fab")
		)
		(fp_line
			(start 0.67945 0.3048)
			(end 0.120396 0.3048)
			(stroke
				(width 0.1)
				(type default)
			)
			(layer "F.Fab")
		)
		(fp_line
			(start 0.120396 0.3048)
			(end 0.120396 0.2794)
			(stroke
				(width 0.1)
				(type default)
			)
			(layer "F.Fab")
		)
		(fp_line
			(start -0.12065 0.3048)
			(end -0.67945 0.3048)
			(stroke
				(width 0.1)
				(type default)
			)
			(layer "F.Fab")
		)
		(fp_line
			(start -0.67945 0.3048)
			(end -0.67945 -0.305054)
			(stroke
				(width 0.1)
				(type default)
			)
			(layer "F.Fab")
		)
		(pad "1" smd circle
			(at -0.40005 0 90)
			(size 0 0)
			(layers "F.Cu" "F.Mask" "F.Paste")
			(net "P12V_NIC1_CO_ISET")
		)
		(pad "2" smd circle
			(at 0.40005 0 90)
			(size 0 0)
			(layers "F.Cu" "F.Mask" "F.Paste")
			(net "P12V_NIC1_CO_ISET_R")
		)
	)
	(footprint ""
		(layer "F.Cu")
		(at 402.641816 -27.006296 -90)
		(property "Reference" "PR7129"
			(at 0 0 270)
			(layer "F.SilkS")
			(hide yes)
			(effects
				(font
					(size 1.27 1.27)
				)
			)
		)
		(property "Value" ""
			(at 0 0 270)
			(layer "F.Fab")
			(effects
				(font
					(size 1.27 1.27)
				)
			)
		)
		(duplicate_pad_numbers_are_jumpers no)
		(fp_line
			(start -0.7874 0.4064)
			(end -0.7874 -0.4064)
			(stroke
				(width 0.1524)
				(type default)
			)
			(layer "F.SilkS")
		)
		(fp_line
			(start 0.7874 0.4064)
			(end -0.7874 0.4064)
			(stroke
				(width 0.1524)
				(type default)
			)
			(layer "F.SilkS")
		)
		(fp_line
			(start -0.7874 -0.4064)
			(end 0.7874 -0.4064)
			(stroke
				(width 0.1524)
				(type default)
			)
			(layer "F.SilkS")
		)
		(fp_line
			(start 0.7874 -0.4064)
			(end 0.7874 0.4064)
			(stroke
				(width 0.1524)
				(type default)
			)
			(layer "F.SilkS")
		)
		(fp_line
			(start -0.67945 0.3048)
			(end -0.67945 -0.305054)
			(stroke
				(width 0.1)
				(type default)
			)
			(layer "F.Fab")
		)
		(fp_line
			(start -0.12065 0.3048)
			(end -0.67945 0.3048)
			(stroke
				(width 0.1)
				(type default)
			)
			(layer "F.Fab")
		)
		(fp_line
			(start 0.120396 0.3048)
			(end 0.120396 0.2794)
			(stroke
				(width 0.1)
				(type default)
			)
			(layer "F.Fab")
		)
		(fp_line
			(start 0.67945 0.3048)
			(end 0.120396 0.3048)
			(stroke
				(width 0.1)
				(type default)
			)
			(layer "F.Fab")
		)
		(fp_line
			(start -0.12065 0.2794)
			(end -0.12065 0.3048)
			(stroke
				(width 0.1)
				(type default)
			)
			(layer "F.Fab")
		)
		(fp_line
			(start 0.120396 0.2794)
			(end -0.12065 0.2794)
			(stroke
				(width 0.1)
				(type default)
			)
			(layer "F.Fab")
		)
		(fp_line
			(start -0.12065 -0.2794)
			(end 0.12065 -0.2794)
			(stroke
				(width 0.1)
				(type default)
			)
			(layer "F.Fab")
		)
		(fp_line
			(start 0.12065 -0.2794)
			(end 0.12065 -0.3048)
			(stroke
				(width 0.1)
				(type default)
			)
			(layer "F.Fab")
		)
		(fp_line
			(start 0.12065 -0.3048)
			(end 0.67945 -0.3048)
			(stroke
				(width 0.1)
				(type default)
			)
			(layer "F.Fab")
		)
		(fp_line
			(start 0.67945 -0.3048)
			(end 0.67945 0.3048)
			(stroke
				(width 0.1)
				(type default)
			)
			(layer "F.Fab")
		)
		(fp_line
			(start -0.67945 -0.305054)
			(end -0.12065 -0.305054)
			(stroke
				(width 0.1)
				(type default)
			)
			(layer "F.Fab")
		)
		(fp_line
			(start -0.12065 -0.305054)
			(end -0.12065 -0.2794)
			(stroke
				(width 0.1)
				(type default)
			)
			(layer "F.Fab")
		)
		(pad "1" smd circle
			(at -0.40005 0 270)
			(size 0 0)
			(layers "F.Cu" "F.Mask" "F.Paste")
			(net "P3V3_SSD14_CO_ILIMIT")
		)
		(pad "2" smd circle
			(at 0.40005 0 270)
			(size 0 0)
			(layers "F.Cu" "F.Mask" "F.Paste")
			(net "GND")
		)
	)
	(footprint ""
		(layer "F.Cu")
		(at 396.209266 -84.928202 180)
		(property "Reference" "R1760"
			(at 0 0 180)
			(layer "F.SilkS")
			(hide yes)
			(effects
				(font
					(size 1.27 1.27)
				)
			)
		)
		(property "Value" ""
			(at 0 0 180)
			(layer "F.Fab")
			(effects
				(font
					(size 1.27 1.27)
				)
			)
		)
		(duplicate_pad_numbers_are_jumpers no)
		(fp_line
			(start 0.7874 0.4064)
			(end -0.7874 0.4064)
			(stroke
				(width 0.1524)
				(type default)
			)
			(layer "F.SilkS")
		)
		(fp_line
			(start 0.7874 -0.4064)
			(end 0.7874 0.4064)
			(stroke
				(width 0.1524)
				(type default)
			)
			(layer "F.SilkS")
		)
		(fp_line
			(start -0.7874 0.4064)
			(end -0.7874 -0.4064)
			(stroke
				(width 0.1524)
				(type default)
			)
			(layer "F.SilkS")
		)
		(fp_line
			(start -0.7874 -0.4064)
			(end 0.7874 -0.4064)
			(stroke
				(width 0.1524)
				(type default)
			)
			(layer "F.SilkS")
		)
		(fp_line
			(start 0.67945 0.3048)
			(end 0.120396 0.3048)
			(stroke
				(width 0.1)
				(type default)
			)
			(layer "F.Fab")
		)
		(fp_line
			(start 0.67945 -0.3048)
			(end 0.67945 0.3048)
			(stroke
				(width 0.1)
				(type default)
			)
			(layer "F.Fab")
		)
		(fp_line
			(start 0.12065 -0.2794)
			(end 0.12065 -0.3048)
			(stroke
				(width 0.1)
				(type default)
			)
			(layer "F.Fab")
		)
		(fp_line
			(start 0.12065 -0.3048)
			(end 0.67945 -0.3048)
			(stroke
				(width 0.1)
				(type default)
			)
			(layer "F.Fab")
		)
		(fp_line
			(start 0.120396 0.3048)
			(end 0.120396 0.2794)
			(stroke
				(width 0.1)
				(type default)
			)
			(layer "F.Fab")
		)
		(fp_line
			(start 0.120396 0.2794)
			(end -0.12065 0.2794)
			(stroke
				(width 0.1)
				(type default)
			)
			(layer "F.Fab")
		)
		(fp_line
			(start -0.12065 0.3048)
			(end -0.67945 0.3048)
			(stroke
				(width 0.1)
				(type default)
			)
			(layer "F.Fab")
		)
		(fp_line
			(start -0.12065 0.2794)
			(end -0.12065 0.3048)
			(stroke
				(width 0.1)
				(type default)
			)
			(layer "F.Fab")
		)
		(fp_line
			(start -0.12065 -0.2794)
			(end 0.12065 -0.2794)
			(stroke
				(width 0.1)
				(type default)
			)
			(layer "F.Fab")
		)
		(fp_line
			(start -0.12065 -0.305054)
			(end -0.12065 -0.2794)
			(stroke
				(width 0.1)
				(type default)
			)
			(layer "F.Fab")
		)
		(fp_line
			(start -0.67945 0.3048)
			(end -0.67945 -0.305054)
			(stroke
				(width 0.1)
				(type default)
			)
			(layer "F.Fab")
		)
		(fp_line
			(start -0.67945 -0.305054)
			(end -0.12065 -0.305054)
			(stroke
				(width 0.1)
				(type default)
			)
			(layer "F.Fab")
		)
		(pad "1" smd circle
			(at -0.40005 0 180)
			(size 0 0)
			(layers "F.Cu" "F.Mask" "F.Paste")
			(net "P3V3_AUX")
		)
		(pad "2" smd circle
			(at 0.40005 0 180)
			(size 0 0)
			(layers "F.Cu" "F.Mask" "F.Paste")
			(net "SMB_BIC_I2C6_MUX_VR_R_SDA")
		)
	)
	(footprint ""
		(layer "F.Cu")
		(at 239.289844 -201.25182)
		(property "Reference" "C3620"
			(at 0 0 0)
			(layer "F.SilkS")
			(hide yes)
			(effects
				(font
					(size 1.27 1.27)
				)
			)
		)
		(property "Value" ""
			(at 0 0 0)
			(layer "F.Fab")
			(effects
				(font
					(size 1.27 1.27)
				)
			)
		)
		(duplicate_pad_numbers_are_jumpers no)
		(fp_line
			(start -0.7874 -0.4064)
			(end 0.7874 -0.4064)
			(stroke
				(width 0.1524)
				(type default)
			)
			(layer "F.SilkS")
		)
		(fp_line
			(start -0.7874 0.4064)
			(end -0.7874 -0.4064)
			(stroke
				(width 0.1524)
				(type default)
			)
			(layer "F.SilkS")
		)
		(fp_line
			(start 0.7874 -0.4064)
			(end 0.7874 0.4064)
			(stroke
				(width 0.1524)
				(type default)
			)
			(layer "F.SilkS")
		)
		(fp_line
			(start 0.7874 0.4064)
			(end -0.7874 0.4064)
			(stroke
				(width 0.1524)
				(type default)
			)
			(layer "F.SilkS")
		)
		(fp_line
			(start -0.67945 -0.305054)
			(end -0.12065 -0.305054)
			(stroke
				(width 0.1)
				(type default)
			)
			(layer "F.Fab")
		)
		(fp_line
			(start -0.67945 0.3048)
			(end -0.67945 -0.305054)
			(stroke
				(width 0.1)
				(type default)
			)
			(layer "F.Fab")
		)
		(fp_line
			(start -0.12065 -0.305054)
			(end -0.12065 -0.2794)
			(stroke
				(width 0.1)
				(type default)
			)
			(layer "F.Fab")
		)
		(fp_line
			(start -0.12065 -0.2794)
			(end 0.12065 -0.2794)
			(stroke
				(width 0.1)
				(type default)
			)
			(layer "F.Fab")
		)
		(fp_line
			(start -0.12065 0.2794)
			(end -0.12065 0.3048)
			(stroke
				(width 0.1)
				(type default)
			)
			(layer "F.Fab")
		)
		(fp_line
			(start -0.12065 0.3048)
			(end -0.67945 0.3048)
			(stroke
				(width 0.1)
				(type default)
			)
			(layer "F.Fab")
		)
		(fp_line
			(start 0.120396 0.2794)
			(end -0.12065 0.2794)
			(stroke
				(width 0.1)
				(type default)
			)
			(layer "F.Fab")
		)
		(fp_line
			(start 0.120396 0.3048)
			(end 0.120396 0.2794)
			(stroke
				(width 0.1)
				(type default)
			)
			(layer "F.Fab")
		)
		(fp_line
			(start 0.12065 -0.3048)
			(end 0.67945 -0.3048)
			(stroke
				(width 0.1)
				(type default)
			)
			(layer "F.Fab")
		)
		(fp_line
			(start 0.12065 -0.2794)
			(end 0.12065 -0.3048)
			(stroke
				(width 0.1)
				(type default)
			)
			(layer "F.Fab")
		)
		(fp_line
			(start 0.67945 -0.3048)
			(end 0.67945 0.3048)
			(stroke
				(width 0.1)
				(type default)
			)
			(layer "F.Fab")
		)
		(fp_line
			(start 0.67945 0.3048)
			(end 0.120396 0.3048)
			(stroke
				(width 0.1)
				(type default)
			)
			(layer "F.Fab")
		)
		(pad "1" smd circle
			(at -0.40005 0)
			(size 0 0)
			(layers "F.Cu" "F.Mask" "F.Paste")
			(net "P3V3_AUX")
		)
		(pad "2" smd circle
			(at 0.40005 0)
			(size 0 0)
			(layers "F.Cu" "F.Mask" "F.Paste")
			(net "GND")
		)
	)
	(footprint ""
		(layer "F.Cu")
		(at 26.991056 -255.359662)
		(property "Reference" "C3065"
			(at 0 0 0)
			(layer "F.SilkS")
			(hide yes)
			(effects
				(font
					(size 1.27 1.27)
				)
			)
		)
		(property "Value" ""
			(at 0 0 0)
			(layer "F.Fab")
			(effects
				(font
					(size 1.27 1.27)
				)
			)
		)
		(duplicate_pad_numbers_are_jumpers no)
		(fp_line
			(start -1.2954 -0.5842)
			(end 1.2954 -0.5842)
			(stroke
				(width 0.1524)
				(type default)
			)
			(layer "F.SilkS")
		)
		(fp_line
			(start -1.2954 0.5842)
			(end -1.2954 -0.5842)
			(stroke
				(width 0.1524)
				(type default)
			)
			(layer "F.SilkS")
		)
		(fp_line
			(start 1.2954 -0.5842)
			(end 1.2954 0.5842)
			(stroke
				(width 0.1524)
				(type default)
			)
			(layer "F.SilkS")
		)
		(fp_line
			(start 1.2954 0.5842)
			(end -1.2954 0.5842)
			(stroke
				(width 0.1524)
				(type default)
			)
			(layer "F.SilkS")
		)
		(fp_line
			(start -1.1938 -0.4064)
			(end -0.8636 -0.4064)
			(stroke
				(width 0.1)
				(type default)
			)
			(layer "F.Fab")
		)
		(fp_line
			(start -1.1938 0.4064)
			(end -1.1938 -0.4064)
			(stroke
				(width 0.1)
				(type default)
			)
			(layer "F.Fab")
		)
		(fp_line
			(start -0.8636 -0.4572)
			(end 0.8636 -0.4572)
			(stroke
				(width 0.1)
				(type default)
			)
			(layer "F.Fab")
		)
		(fp_line
			(start -0.8636 -0.4064)
			(end -0.8636 -0.4572)
			(stroke
				(width 0.1)
				(type default)
			)
			(layer "F.Fab")
		)
		(fp_line
			(start -0.8636 0.4064)
			(end -1.1938 0.4064)
			(stroke
				(width 0.1)
				(type default)
			)
			(layer "F.Fab")
		)
		(fp_line
			(start -0.8636 0.4572)
			(end -0.8636 0.4064)
			(stroke
				(width 0.1)
				(type default)
			)
			(layer "F.Fab")
		)
		(fp_line
			(start 0.8636 -0.4572)
			(end 0.8636 -0.4064)
			(stroke
				(width 0.1)
				(type default)
			)
			(layer "F.Fab")
		)
		(fp_line
			(start 0.8636 -0.4064)
			(end 1.1938 -0.4064)
			(stroke
				(width 0.1)
				(type default)
			)
			(layer "F.Fab")
		)
		(fp_line
			(start 0.8636 0.4064)
			(end 0.8636 0.4572)
			(stroke
				(width 0.1)
				(type default)
			)
			(layer "F.Fab")
		)
		(fp_line
			(start 0.8636 0.4572)
			(end -0.8636 0.4572)
			(stroke
				(width 0.1)
				(type default)
			)
			(layer "F.Fab")
		)
		(fp_line
			(start 1.1938 -0.4064)
			(end 1.1938 0.4064)
			(stroke
				(width 0.1)
				(type default)
			)
			(layer "F.Fab")
		)
		(fp_line
			(start 1.1938 0.4064)
			(end 0.8636 0.4064)
			(stroke
				(width 0.1)
				(type default)
			)
			(layer "F.Fab")
		)
		(pad "1" smd rect
			(at -0.7366 0 270)
			(size 0.7112 0.8128)
			(layers "F.Cu" "F.Mask" "F.Paste")
			(net "P1V8_PLL0_PEX0")
		)
		(pad "2" smd rect
			(at 0.7366 0 270)
			(size 0.7112 0.8128)
			(layers "F.Cu" "F.Mask" "F.Paste")
			(net "GND")
		)
	)
)
